# S9S_MB_2U (Grand Teton) — schematic netlist excerpt (pin names and nets, part order shuffled) for the footprints in the layout excerpt that follows; sources: Cadence DE-HDL packaged netlist, KiCad conversion of 03242023_DA0F0TMBIJ0_F0T_Motherboard_J_brd_V01_OCP.brd

PR2516  Q_RES  10 1% EMPTY  pkg 0402LF  page 304 : A = P12V_HSC_ADC_N ; B = P12V_HSC_SENSE2_R2_N
R24  Q_RES  10 1% CHIP  pkg 0402LF  page 16 : A = DBP_CPU0_HOOK8_MBP2_GTL_QS_R_N ; B = DBP_CPU_HOOK8_MBP2_GTL_QS_N

(kicad_pcb
	(version 20260206)
	(generator "pcbnew")
	(generator_version "10.0")
	(general
		(thickness 1.6)
		(legacy_teardrops no)
	)
	(paper "A4")
	(title_block
		(title "03242023_DA0F0TMBIJ0_F0T_Motherboard_J_brd_V01_OCP.brd")
		(comment 1 "Grand Teton / footprints 4263-4264 of 6105")
	)
	(layers
		(0 "F.Cu" signal "TOP")
		(4 "In1.Cu" signal "GND")
		(6 "In2.Cu" signal "IN1")
		(8 "In3.Cu" signal "GND1")
		(10 "In4.Cu" signal "IN2")
		(12 "In5.Cu" signal "GND2")
		(14 "In6.Cu" signal "IN3")
		(16 "In7.Cu" signal "GND3")
		(18 "In8.Cu" signal "VCC")
		(20 "In9.Cu" signal "VCC1")
		(22 "In10.Cu" signal "GND4")
		(24 "In11.Cu" signal "IN4")
		(26 "In12.Cu" signal "GND5")
		(28 "In13.Cu" signal "IN5")
		(30 "In14.Cu" signal "GND6")
		(32 "In15.Cu" signal "IN6")
		(34 "In16.Cu" signal "GND7")
		(2 "B.Cu" signal "BOTTOM")
		(9 "F.Adhes" user "F.Adhesive")
		(11 "B.Adhes" user "B.Adhesive")
		(13 "F.Paste" user "Package Geometry/Pastemask Top")
		(15 "B.Paste" user "Package Geometry/Pastemask Bottom")
		(5 "F.SilkS" user "Ref Des/Silkscreen Top")
		(7 "B.SilkS" user "Ref Des/Silkscreen Bottom")
		(1 "F.Mask" user "Board Geometry/Soldermask Top")
		(3 "B.Mask" user "Board Geometry/Soldermask Bottom")
		(17 "Dwgs.User" user "User.Drawings")
		(19 "Cmts.User" user "User.Comments")
		(21 "Eco1.User" user "User.Eco1")
		(23 "Eco2.User" user "User.Eco2")
		(25 "Edge.Cuts" user "Board Geometry/Outline")
		(27 "Margin" user)
		(31 "F.CrtYd" user "Package Geometry/Place Bound Top")
		(29 "B.CrtYd" user "Package Geometry/Place Bound Bottom")
		(35 "F.Fab" user "Ref Des/Assembly Top")
		(33 "B.Fab" user "Ref Des/Assembly Bottom")
	)
	(footprint ""
		(layer "B.Cu")
		(at 289.988498 -403.031452 90)
		(property "Reference" "PR2516"
			(at 0 0 90)
			(layer "B.SilkS")
			(hide yes)
			(effects
				(font
					(size 1.27 1.27)
				)
				(justify mirror)
			)
		)
		(property "Value" ""
			(at 0 0 90)
			(layer "B.Fab")
			(effects
				(font
					(size 1.27 1.27)
				)
				(justify mirror)
			)
		)
		(duplicate_pad_numbers_are_jumpers no)
		(fp_line
			(start 0.7874 -0.4064)
			(end -0.7874 -0.4064)
			(stroke
				(width 0.1524)
				(type default)
			)
			(layer "B.SilkS")
		)
		(fp_line
			(start -0.7874 -0.4064)
			(end -0.7874 0.4064)
			(stroke
				(width 0.1524)
				(type default)
			)
			(layer "B.SilkS")
		)
		(fp_line
			(start 0.7874 0.4064)
			(end 0.7874 -0.4064)
			(stroke
				(width 0.1524)
				(type default)
			)
			(layer "B.SilkS")
		)
		(fp_line
			(start -0.7874 0.4064)
			(end 0.7874 0.4064)
			(stroke
				(width 0.1524)
				(type default)
			)
			(layer "B.SilkS")
		)
		(fp_line
			(start 0.67945 -0.305054)
			(end 0.12065 -0.305054)
			(stroke
				(width 0.1)
				(type default)
			)
			(layer "B.Fab")
		)
		(fp_line
			(start 0.12065 -0.305054)
			(end 0.12065 -0.2794)
			(stroke
				(width 0.1)
				(type default)
			)
			(layer "B.Fab")
		)
		(fp_line
			(start -0.12065 -0.3048)
			(end -0.67945 -0.3048)
			(stroke
				(width 0.1)
				(type default)
			)
			(layer "B.Fab")
		)
		(fp_line
			(start -0.67945 -0.3048)
			(end -0.67945 0.3048)
			(stroke
				(width 0.1)
				(type default)
			)
			(layer "B.Fab")
		)
		(fp_line
			(start 0.12065 -0.2794)
			(end -0.12065 -0.2794)
			(stroke
				(width 0.1)
				(type default)
			)
			(layer "B.Fab")
		)
		(fp_line
			(start -0.12065 -0.2794)
			(end -0.12065 -0.3048)
			(stroke
				(width 0.1)
				(type default)
			)
			(layer "B.Fab")
		)
		(fp_line
			(start 0.12065 0.2794)
			(end 0.12065 0.3048)
			(stroke
				(width 0.1)
				(type default)
			)
			(layer "B.Fab")
		)
		(fp_line
			(start -0.120396 0.2794)
			(end 0.12065 0.2794)
			(stroke
				(width 0.1)
				(type default)
			)
			(layer "B.Fab")
		)
		(fp_line
			(start 0.67945 0.3048)
			(end 0.67945 -0.305054)
			(stroke
				(width 0.1)
				(type default)
			)
			(layer "B.Fab")
		)
		(fp_line
			(start 0.12065 0.3048)
			(end 0.67945 0.3048)
			(stroke
				(width 0.1)
				(type default)
			)
			(layer "B.Fab")
		)
		(fp_line
			(start -0.120396 0.3048)
			(end -0.120396 0.2794)
			(stroke
				(width 0.1)
				(type default)
			)
			(layer "B.Fab")
		)
		(fp_line
			(start -0.67945 0.3048)
			(end -0.120396 0.3048)
			(stroke
				(width 0.1)
				(type default)
			)
			(layer "B.Fab")
		)
		(pad "1" smd circle
			(at 0.40005 0 270)
			(size 0 0)
			(layers "B.Cu" "B.Mask" "B.Paste")
			(net "P12V_HSC_ADC_N")
		)
		(pad "2" smd circle
			(at -0.40005 0 270)
			(size 0 0)
			(layers "B.Cu" "B.Mask" "B.Paste")
			(net "P12V_HSC_SENSE2_R2_N")
		)
	)
	(footprint ""
		(layer "B.Cu")
		(at 331.540358 -190.82893 90)
		(property "Reference" "R24"
			(at 0 0 90)
			(layer "B.SilkS")
			(hide yes)
			(effects
				(font
					(size 1.27 1.27)
				)
				(justify mirror)
			)
		)
		(property "Value" ""
			(at 0 0 90)
			(layer "B.Fab")
			(effects
				(font
					(size 1.27 1.27)
				)
				(justify mirror)
			)
		)
		(duplicate_pad_numbers_are_jumpers no)
		(fp_line
			(start 0.7874 -0.4064)
			(end -0.7874 -0.4064)
			(stroke
				(width 0.1524)
				(type default)
			)
			(layer "B.SilkS")
		)
		(fp_line
			(start -0.7874 -0.4064)
			(end -0.7874 0.4064)
			(stroke
				(width 0.1524)
				(type default)
			)
			(layer "B.SilkS")
		)
		(fp_line
			(start 0.7874 0.4064)
			(end 0.7874 -0.4064)
			(stroke
				(width 0.1524)
				(type default)
			)
			(layer "B.SilkS")
		)
		(fp_line
			(start -0.7874 0.4064)
			(end 0.7874 0.4064)
			(stroke
				(width 0.1524)
				(type default)
			)
			(layer "B.SilkS")
		)
		(fp_line
			(start 0.67945 -0.305054)
			(end 0.12065 -0.305054)
			(stroke
				(width 0.1)
				(type default)
			)
			(layer "B.Fab")
		)
		(fp_line
			(start 0.12065 -0.305054)
			(end 0.12065 -0.2794)
			(stroke
				(width 0.1)
				(type default)
			)
			(layer "B.Fab")
		)
		(fp_line
			(start -0.12065 -0.3048)
			(end -0.67945 -0.3048)
			(stroke
				(width 0.1)
				(type default)
			)
			(layer "B.Fab")
		)
		(fp_line
			(start -0.67945 -0.3048)
			(end -0.67945 0.3048)
			(stroke
				(width 0.1)
				(type default)
			)
			(layer "B.Fab")
		)
		(fp_line
			(start 0.12065 -0.2794)
			(end -0.12065 -0.2794)
			(stroke
				(width 0.1)
				(type default)
			)
			(layer "B.Fab")
		)
		(fp_line
			(start -0.12065 -0.2794)
			(end -0.12065 -0.3048)
			(stroke
				(width 0.1)
				(type default)
			)
			(layer "B.Fab")
		)
		(fp_line
			(start 0.12065 0.2794)
			(end 0.12065 0.3048)
			(stroke
				(width 0.1)
				(type default)
			)
			(layer "B.Fab")
		)
		(fp_line
			(start -0.120396 0.2794)
			(end 0.12065 0.2794)
			(stroke
				(width 0.1)
				(type default)
			)
			(layer "B.Fab")
		)
		(fp_line
			(start 0.67945 0.3048)
			(end 0.67945 -0.305054)
			(stroke
				(width 0.1)
				(type default)
			)
			(layer "B.Fab")
		)
		(fp_line
			(start 0.12065 0.3048)
			(end 0.67945 0.3048)
			(stroke
				(width 0.1)
				(type default)
			)
			(layer "B.Fab")
		)
		(fp_line
			(start -0.120396 0.3048)
			(end -0.120396 0.2794)
			(stroke
				(width 0.1)
				(type default)
			)
			(layer "B.Fab")
		)
		(fp_line
			(start -0.67945 0.3048)
			(end -0.120396 0.3048)
			(stroke
				(width 0.1)
				(type default)
			)
			(layer "B.Fab")
		)
		(pad "1" smd circle
			(at 0.40005 0 270)
			(size 0 0)
			(layers "B.Cu" "B.Mask" "B.Paste")
			(net "DBP_CPU0_HOOK8_MBP2_GTL_QS_R_N")
		)
		(pad "2" smd circle
			(at -0.40005 0 270)
			(size 0 0)
			(layers "B.Cu" "B.Mask" "B.Paste")
			(net "DBP_CPU_HOOK8_MBP2_GTL_QS_N")
		)
	)
)
